(kicad_pcb
	(version 20260206)
	(generator "pcbnew")
	(generator_version "10.0")
	(general
		(thickness 0.77098)
		(legacy_teardrops no)
	)
	(paper "A4")
	(title_block
		(title "gnss-m2-zed-f9t — M2_ZED-F9T_MODULE.PcbDoc")
		(comment 1 "Time Appliance Project (Time Card) / footprints 13-14 of 36")
	)
	(layers
		(0 "F.Cu" signal "L01-Top Layer")
		(4 "In1.Cu" signal "L02-Inner Layer")
		(6 "In2.Cu" signal "L03-Inner Layer")
		(2 "B.Cu" signal "L04-Bottom Layer")
		(9 "F.Adhes" user "F.Adhesive")
		(11 "B.Adhes" user "B.Adhesive")
		(13 "F.Paste" user "Top Paste")
		(15 "B.Paste" user "Bottom Paste")
		(5 "F.SilkS" user "Top Overlay")
		(7 "B.SilkS" user "Bottom Overlay")
		(1 "F.Mask" user "Top Solder")
		(3 "B.Mask" user "Bottom Solder")
		(17 "Dwgs.User" user "User.Drawings")
		(19 "Cmts.User" user "User.Comments")
		(21 "Eco1.User" user "User.Eco1")
		(23 "Eco2.User" user "User.Eco2")
		(25 "Edge.Cuts" user)
		(27 "Margin" user)
		(31 "F.CrtYd" user "Top Courtyard")
		(29 "B.CrtYd" user "Bottom Courtyard")
		(35 "F.Fab" user "Top Component Outline")
		(33 "B.Fab" user "Bottom Component Outline 2")
	)
	(footprint "GNSS_Receiver_Library:GPS_ZED-F9T"
		(locked yes)
		(layer "F.Cu")
		(at 155.701105 93.84359 180)
		(property "Reference" "U1"
			(at -3 1.84474 0)
			(unlocked yes)
			(layer "F.SilkS")
			(effects
				(font
					(face "Arial")
					(size 0.504 0.504)
					(thickness 0.15)
				)
			)
		)
		(property "Value" "ZED-F9T-00B"
			(at 3.059145 -26.098741 0)
			(unlocked yes)
			(layer "F.SilkS")
			(hide yes)
			(effects
				(font
					(face "Arial")
					(size 0.96012 0.96012)
					(thickness 0.254)
				)
			)
		)
		(sheetname "01-M2_ZED-F9T_MODULE")
		(sheetfile "01-M2_ZED-F9T_MODULE.kicad_sch")
		(duplicate_pad_numbers_are_jumpers no)
		(fp_circle
			(center -0.5 2.23999)
			(end -0.5 2.31619)
			(stroke
				(width 0.762)
				(type solid)
			)
			(fill no)
			(layer "F.SilkS")
		)
		(pad "1" smd rect
			(at 0 0 180)
			(size 0.8 1.5)
			(layers "F.Cu" "F.Mask" "F.Paste")
			(net "GND")
		)
		(pad "2" smd rect
			(at 1.1 0 180)
			(size 0.8 1.5)
			(layers "F.Cu" "F.Mask" "F.Paste")
			(net "RF_IN")
		)
		(pad "3" smd rect
			(at 2.2 0 180)
			(size 0.8 1.5)
			(layers "F.Cu" "F.Mask" "F.Paste")
			(net "GND")
		)
		(pad "4" smd rect
			(at 3.3 0 180)
			(size 0.8 1.5)
			(layers "F.Cu" "F.Mask" "F.Paste")
			(net "ANT_DET")
		)
		(pad "5" smd rect
			(at 4.4 0 180)
			(size 0.8 1.5)
			(layers "F.Cu" "F.Mask" "F.Paste")
			(net "ANT_OFF")
		)
		(pad "6" smd rect
			(at 5.5 0 180)
			(size 0.8 1.5)
			(layers "F.Cu" "F.Mask" "F.Paste")
			(net "ANT_SHORT_N")
		)
		(pad "7" smd rect
			(at 6.6 0 180)
			(size 0.8 1.5)
			(layers "F.Cu" "F.Mask" "F.Paste")
		)
		(pad "8" smd rect
			(at 7.7 0 180)
			(size 0.8 1.5)
			(layers "F.Cu" "F.Mask" "F.Paste")
		)
		(pad "9" smd rect
			(at 8.8 0 180)
			(size 0.8 1.5)
			(layers "F.Cu" "F.Mask" "F.Paste")
		)
		(pad "10" smd rect
			(at 9.9 0 180)
			(size 0.8 1.5)
			(layers "F.Cu" "F.Mask" "F.Paste")
		)
		(pad "11" smd rect
			(at 11 0 180)
			(size 0.8 1.5)
			(layers "F.Cu" "F.Mask" "F.Paste")
		)
		(pad "12" smd rect
			(at 12.1 0 180)
			(size 0.8 1.5)
			(layers "F.Cu" "F.Mask" "F.Paste")
			(net "GND")
		)
		(pad "13" smd rect
			(at 13.2 0 180)
			(size 0.8 1.5)
			(layers "F.Cu" "F.Mask" "F.Paste")
		)
		(pad "14" smd rect
			(at 14.3 0 180)
			(size 0.8 1.5)
			(layers "F.Cu" "F.Mask" "F.Paste")
			(net "GND")
		)
		(pad "15" smd rect
			(at 17.1 -0.85 270)
			(size 0.8 1.5)
			(layers "F.Cu" "F.Mask" "F.Paste")
		)
		(pad "16" smd rect
			(at 17.1 -1.95 270)
			(size 0.8 1.5)
			(layers "F.Cu" "F.Mask" "F.Paste")
		)
		(pad "17" smd rect
			(at 17.1 -3.05 270)
			(size 0.8 1.5)
			(layers "F.Cu" "F.Mask" "F.Paste")
		)
		(pad "18" smd rect
			(at 17.1 -4.15 270)
			(size 0.8 1.5)
			(layers "F.Cu" "F.Mask" "F.Paste")
		)
		(pad "19" smd rect
			(at 17.1 -5.25 270)
			(size 0.8 1.5)
			(layers "F.Cu" "F.Mask" "F.Paste")
		)
		(pad "20" smd rect
			(at 17.1 -6.35 270)
			(size 0.8 1.5)
			(layers "F.Cu" "F.Mask" "F.Paste")
		)
		(pad "21" smd rect
			(at 17.1 -7.45 270)
			(size 0.8 1.5)
			(layers "F.Cu" "F.Mask" "F.Paste")
		)
		(pad "22" smd rect
			(at 17.1 -8.55 270)
			(size 0.8 1.5)
			(layers "F.Cu" "F.Mask" "F.Paste")
		)
		(pad "23" smd rect
			(at 17.1 -9.65 270)
			(size 0.8 1.5)
			(layers "F.Cu" "F.Mask" "F.Paste")
		)
		(pad "24" smd rect
			(at 17.1 -10.75 270)
			(size 0.8 1.5)
			(layers "F.Cu" "F.Mask" "F.Paste")
		)
		(pad "25" smd rect
			(at 17.1 -11.85 270)
			(size 0.8 1.5)
			(layers "F.Cu" "F.Mask" "F.Paste")
		)
		(pad "26" smd rect
			(at 17.1 -12.95 270)
			(size 0.8 1.5)
			(layers "F.Cu" "F.Mask" "F.Paste")
		)
		(pad "27" smd rect
			(at 17.1 -14.05 270)
			(size 0.8 1.5)
			(layers "F.Cu" "F.Mask" "F.Paste")
		)
		(pad "28" smd rect
			(at 14.3 -14.9 180)
			(size 0.8 1.5)
			(layers "F.Cu" "F.Mask" "F.Paste")
		)
		(pad "29" smd rect
			(at 13.2 -14.9 180)
			(size 0.8 1.5)
			(layers "F.Cu" "F.Mask" "F.Paste")
		)
		(pad "30" smd rect
			(at 12.1 -14.9 180)
			(size 0.8 1.5)
			(layers "F.Cu" "F.Mask" "F.Paste")
		)
		(pad "31" smd rect
			(at 11 -14.9 180)
			(size 0.8 1.5)
			(layers "F.Cu" "F.Mask" "F.Paste")
		)
		(pad "32" smd rect
			(at 9.9 -14.9 180)
			(size 0.8 1.5)
			(layers "F.Cu" "F.Mask" "F.Paste")
			(net "GND")
		)
		(pad "33" smd rect
			(at 8.8 -14.9 180)
			(size 0.8 1.5)
			(layers "F.Cu" "F.Mask" "F.Paste")
			(net "+3V3")
		)
		(pad "34" smd rect
			(at 7.7 -14.9 180)
			(size 0.8 1.5)
			(layers "F.Cu" "F.Mask" "F.Paste")
			(net "+3V3")
		)
		(pad "35" smd rect
			(at 6.6 -14.9 180)
			(size 0.8 1.5)
			(layers "F.Cu" "F.Mask" "F.Paste")
		)
		(pad "36" smd rect
			(at 5.5 -14.9 180)
			(size 0.8 1.5)
			(layers "F.Cu" "F.Mask" "F.Paste")
			(net "+3V3")
		)
		(pad "37" smd rect
			(at 4.4 -14.9 180)
			(size 0.8 1.5)
			(layers "F.Cu" "F.Mask" "F.Paste")
			(net "GND")
		)
		(pad "38" smd rect
			(at 3.3 -14.9 180)
			(size 0.8 1.5)
			(layers "F.Cu" "F.Mask" "F.Paste")
			(net "GND")
		)
		(pad "39" smd rect
			(at 2.2 -14.9 180)
			(size 0.8 1.5)
			(layers "F.Cu" "F.Mask" "F.Paste")
			(net "USB_D_N")
		)
		(pad "40" smd rect
			(at 1.1 -14.9 180)
			(size 0.8 1.5)
			(layers "F.Cu" "F.Mask" "F.Paste")
			(net "USB_D_P")
		)
		(pad "41" smd rect
			(at 0 -14.9 180)
			(size 0.8 1.5)
			(layers "F.Cu" "F.Mask" "F.Paste")
			(net "GND")
		)
		(pad "42" smd rect
			(at -2.8 -14.05 270)
			(size 0.8 1.5)
			(layers "F.Cu" "F.Mask" "F.Paste")
			(net "NetR2_2")
		)
		(pad "43" smd rect
			(at -2.8 -12.95 270)
			(size 0.8 1.5)
			(layers "F.Cu" "F.Mask" "F.Paste")
			(net "NetR3_2")
		)
		(pad "44" smd rect
			(at -2.8 -11.85 270)
			(size 0.8 1.5)
			(layers "F.Cu" "F.Mask" "F.Paste")
			(net "SDA")
		)
		(pad "45" smd rect
			(at -2.8 -10.75 270)
			(size 0.8 1.5)
			(layers "F.Cu" "F.Mask" "F.Paste")
			(net "SCL")
		)
		(pad "46" smd rect
			(at -2.8 -9.65 270)
			(size 0.8 1.5)
			(layers "F.Cu" "F.Mask" "F.Paste")
		)
		(pad "47" smd rect
			(at -2.8 -8.55 270)
			(size 0.8 1.5)
			(layers "F.Cu" "F.Mask" "F.Paste")
			(net "NetC5_2")
		)
		(pad "48" smd rect
			(at -2.8 -7.45 270)
			(size 0.8 1.5)
			(layers "F.Cu" "F.Mask" "F.Paste")
			(net "GND")
		)
		(pad "49" smd rect
			(at -2.8 -6.35 270)
			(size 0.8 1.5)
			(layers "F.Cu" "F.Mask" "F.Paste")
			(net "RST_GPS")
		)
		(pad "50" smd rect
			(at -2.8 -5.25 270)
			(size 0.8 1.5)
			(layers "F.Cu" "F.Mask" "F.Paste")
		)
		(pad "51" smd rect
			(at -2.8 -4.15 270)
			(size 0.8 1.5)
			(layers "F.Cu" "F.Mask" "F.Paste")
		)
		(pad "52" smd rect
			(at -2.8 -3.05 270)
			(size 0.8 1.5)
			(layers "F.Cu" "F.Mask" "F.Paste")
		)
		(pad "53" smd rect
			(at -2.8 -1.95 270)
			(size 0.8 1.5)
			(layers "F.Cu" "F.Mask" "F.Paste")
			(net "TP1")
		)
		(pad "54" smd rect
			(at -2.8 -0.85 270)
			(size 0.8 1.5)
			(layers "F.Cu" "F.Mask" "F.Paste")
			(net "TP2")
		)
		(pad "55" smd rect
			(at -0.2 -12.69998 180)
			(size 1.1 1.1)
			(layers "F.Cu" "F.Mask" "F.Paste")
			(net "GND")
		)
		(pad "55" smd rect
			(at -0.2 -10.59999 180)
			(size 1.1 1.1)
			(layers "F.Cu" "F.Mask" "F.Paste")
			(net "GND")
		)
		(pad "55" smd rect
			(at -0.2 -8.49999 180)
			(size 1.1 1.1)
			(layers "F.Cu" "F.Mask" "F.Paste")
			(net "GND")
		)
		(pad "55" smd rect
			(at -0.2 -6.4 180)
			(size 1.1 1.1)
			(layers "F.Cu" "F.Mask" "F.Paste")
			(net "GND")
		)
		(pad "55" smd rect
			(at -0.2 -4.3 180)
			(size 1.1 1.1)
			(layers "F.Cu" "F.Mask" "F.Paste")
			(net "GND")
		)
		(pad "55" smd rect
			(at -0.2 -2.2 180)
			(size 1.1 1.1)
			(layers "F.Cu" "F.Mask" "F.Paste")
			(net "GND")
		)
		(pad "55" smd rect
			(at 1.9 -12.69998 180)
			(size 1.1 1.1)
			(layers "F.Cu" "F.Mask" "F.Paste")
			(net "GND")
		)
		(pad "55" smd rect
			(at 1.9 -10.59998 180)
			(size 1.1 1.1)
			(layers "F.Cu" "F.Mask" "F.Paste")
			(net "GND")
		)
		(pad "55" smd rect
			(at 1.9 -8.49999 180)
			(size 1.1 1.1)
			(layers "F.Cu" "F.Mask" "F.Paste")
			(net "GND")
		)
		(pad "55" smd rect
			(at 1.9 -6.39999 180)
			(size 1.1 1.1)
			(layers "F.Cu" "F.Mask" "F.Paste")
			(net "GND")
		)
		(pad "55" smd rect
			(at 1.9 -4.29999 180)
			(size 1.1 1.1)
			(layers "F.Cu" "F.Mask" "F.Paste")
			(net "GND")
		)
		(pad "55" smd rect
			(at 1.9 -2.2 180)
			(size 1.1 1.1)
			(layers "F.Cu" "F.Mask" "F.Paste")
			(net "GND")
		)
		(pad "55" smd rect
			(at 4 -12.69998 180)
			(size 1.1 1.1)
			(layers "F.Cu" "F.Mask" "F.Paste")
			(net "GND")
		)
		(pad "55" smd rect
			(at 4 -10.59998 180)
			(size 1.1 1.1)
			(layers "F.Cu" "F.Mask" "F.Paste")
			(net "GND")
		)
		(pad "55" smd rect
			(at 4 -8.49999 180)
			(size 1.1 1.1)
			(layers "F.Cu" "F.Mask" "F.Paste")
			(net "GND")
		)
		(pad "55" smd rect
			(at 4 -6.39999 180)
			(size 1.1 1.1)
			(layers "F.Cu" "F.Mask" "F.Paste")
			(net "GND")
		)
		(pad "55" smd rect
			(at 4 -4.29999 180)
			(size 1.1 1.1)
			(layers "F.Cu" "F.Mask" "F.Paste")
			(net "GND")
		)
		(pad "55" smd rect
			(at 4 -2.2 180)
			(size 1.1 1.1)
			(layers "F.Cu" "F.Mask" "F.Paste")
			(net "GND")
		)
		(pad "55" smd rect
			(at 6.1 -12.69998 180)
			(size 1.1 1.1)
			(layers "F.Cu" "F.Mask" "F.Paste")
			(net "GND")
		)
		(pad "55" smd rect
			(at 6.1 -10.59998 180)
			(size 1.1 1.1)
			(layers "F.Cu" "F.Mask" "F.Paste")
			(net "GND")
		)
		(pad "55" smd rect
			(at 6.1 -8.49999 180)
			(size 1.1 1.1)
			(layers "F.Cu" "F.Mask" "F.Paste")
			(net "GND")
		)
		(pad "55" smd rect
			(at 6.1 -6.39999 180)
			(size 1.1 1.1)
			(layers "F.Cu" "F.Mask" "F.Paste")
			(net "GND")
		)
		(pad "55" smd rect
			(at 6.1 -4.29999 180)
			(size 1.1 1.1)
			(layers "F.Cu" "F.Mask" "F.Paste")
			(net "GND")
		)
		(pad "55" smd rect
			(at 6.1 -2.2 180)
			(size 1.1 1.1)
			(layers "F.Cu" "F.Mask" "F.Paste")
			(net "GND")
		)
		(pad "55" smd rect
			(at 8.2 -12.69998 180)
			(size 1.1 1.1)
			(layers "F.Cu" "F.Mask" "F.Paste")
			(net "GND")
		)
		(pad "55" smd rect
			(at 8.2 -10.59998 180)
			(size 1.1 1.1)
			(layers "F.Cu" "F.Mask" "F.Paste")
			(net "GND")
		)
		(pad "55" smd rect
			(at 8.2 -8.49999 180)
			(size 1.1 1.1)
			(layers "F.Cu" "F.Mask" "F.Paste")
			(net "GND")
		)
		(pad "55" smd rect
			(at 8.2 -6.39999 180)
			(size 1.1 1.1)
			(layers "F.Cu" "F.Mask" "F.Paste")
			(net "GND")
		)
		(pad "55" smd rect
			(at 8.2 -4.29999 180)
			(size 1.1 1.1)
			(layers "F.Cu" "F.Mask" "F.Paste")
			(net "GND")
		)
		(pad "55" smd rect
			(at 8.2 -2.2 180)
			(size 1.1 1.1)
			(layers "F.Cu" "F.Mask" "F.Paste")
			(net "GND")
		)
		(pad "55" smd rect
			(at 10.3 -12.69998 180)
			(size 1.1 1.1)
			(layers "F.Cu" "F.Mask" "F.Paste")
			(net "GND")
		)
		(pad "55" smd rect
			(at 10.3 -10.59998 180)
			(size 1.1 1.1)
			(layers "F.Cu" "F.Mask" "F.Paste")
			(net "GND")
		)
		(pad "55" smd rect
			(at 10.3 -8.49999 180)
			(size 1.1 1.1)
			(layers "F.Cu" "F.Mask" "F.Paste")
			(net "GND")
		)
		(pad "55" smd rect
			(at 10.3 -6.39999 180)
			(size 1.1 1.1)
			(layers "F.Cu" "F.Mask" "F.Paste")
			(net "GND")
		)
		(pad "55" smd rect
			(at 10.3 -4.29999 180)
			(size 1.1 1.1)
			(layers "F.Cu" "F.Mask" "F.Paste")
			(net "GND")
		)
		(pad "55" smd rect
			(at 10.3 -2.2 180)
			(size 1.1 1.1)
			(layers "F.Cu" "F.Mask" "F.Paste")
			(net "GND")
		)
		(pad "55" smd rect
			(at 12.4 -12.69998 180)
			(size 1.1 1.1)
			(layers "F.Cu" "F.Mask" "F.Paste")
			(net "GND")
		)
		(pad "55" smd rect
			(at 12.4 -10.59998 180)
			(size 1.1 1.1)
			(layers "F.Cu" "F.Mask" "F.Paste")
			(net "GND")
		)
		(pad "55" smd rect
			(at 12.4 -8.49999 180)
			(size 1.1 1.1)
			(layers "F.Cu" "F.Mask" "F.Paste")
			(net "GND")
		)
		(pad "55" smd rect
			(at 12.4 -6.39999 180)
			(size 1.1 1.1)
			(layers "F.Cu" "F.Mask" "F.Paste")
			(net "GND")
		)
		(pad "55" smd rect
			(at 12.4 -4.29999 180)
			(size 1.1 1.1)
			(layers "F.Cu" "F.Mask" "F.Paste")
			(net "GND")
		)
		(pad "55" smd rect
			(at 12.4 -2.2 180)
			(size 1.1 1.1)
			(layers "F.Cu" "F.Mask" "F.Paste")
			(net "GND")
		)
		(pad "55" smd rect
			(at 14.5 -12.69998 180)
			(size 1.1 1.1)
			(layers "F.Cu" "F.Mask" "F.Paste")
			(net "GND")
		)
		(pad "55" smd rect
			(at 14.5 -10.59998 180)
			(size 1.1 1.1)
			(layers "F.Cu" "F.Mask" "F.Paste")
			(net "GND")
		)
		(pad "55" smd rect
			(at 14.5 -8.49999 180)
			(size 1.1 1.1)
			(layers "F.Cu" "F.Mask" "F.Paste")
			(net "GND")
		)
		(pad "55" smd rect
			(at 14.5 -6.39999 180)
			(size 1.1 1.1)
			(layers "F.Cu" "F.Mask" "F.Paste")
			(net "GND")
		)
		(pad "55" smd rect
			(at 14.5 -4.29999 180)
			(size 1.1 1.1)
			(layers "F.Cu" "F.Mask" "F.Paste")
			(net "GND")
		)
		(pad "55" smd rect
			(at 14.5 -2.2 180)
			(size 1.1 1.1)
			(layers "F.Cu" "F.Mask" "F.Paste")
			(net "GND")
		)
	)
	(footprint "Vault:FP-RMCF0402-MFG"
		(layer "F.Cu")
		(at 143.901105 112.0036 180)
		(property "Reference" "R1"
			(at 0.1 1.279605 0)
			(unlocked yes)
			(layer "F.SilkS")
			(effects
				(font
					(face "Arial")
					(size 0.40005 0.40005)
					(thickness 0.1778)
				)
			)
		)
		(property "Value" "1k"
			(at 2.729345 2.066945 180)
			(unlocked yes)
			(layer "F.SilkS")
			(hide yes)
			(effects
				(font
					(face "Arial")
					(size 0.40005 0.40005)
					(thickness 0.1778)
				)
			)
		)
		(sheetname "01-M2_ZED-F9T_MODULE")
		(sheetfile "01-M2_ZED-F9T_MODULE.kicad_sch")
		(duplicate_pad_numbers_are_jumpers no)
		(fp_line
			(start 0.55 0.7)
			(end -0.55 0.7)
			(stroke
				(width 0.2)
				(type solid)
			)
			(layer "F.SilkS")
		)
		(fp_line
			(start 0.55 -0.7)
			(end -0.55 -0.7)
			(stroke
				(width 0.2)
				(type solid)
			)
			(layer "F.SilkS")
		)
		(fp_line
			(start 0.85 0.4)
			(end -0.85 0.4)
			(stroke
				(width 0.2)
				(type solid)
			)
			(layer "F.CrtYd")
		)
		(fp_line
			(start 0.85 -0.4)
			(end 0.85 0.4)
			(stroke
				(width 0.2)
				(type solid)
			)
			(layer "F.CrtYd")
		)
		(fp_line
			(start 0.85 -0.4)
			(end -0.85 -0.4)
			(stroke
				(width 0.2)
				(type solid)
			)
			(layer "F.CrtYd")
		)
		(fp_line
			(start -0.85 -0.4)
			(end -0.85 0.4)
			(stroke
				(width 0.2)
				(type solid)
			)
			(layer "F.CrtYd")
		)
		(fp_line
			(start 0.85 0.4)
			(end -0.85 0.4)
			(stroke
				(width 0.2)
				(type solid)
			)
			(layer "F.Fab")
		)
		(fp_line
			(start 0.85 -0.4)
			(end 0.85 0.4)
			(stroke
				(width 0.2)
				(type solid)
			)
			(layer "F.Fab")
		)
		(fp_line
			(start 0.85 -0.4)
			(end -0.85 -0.4)
			(stroke
				(width 0.2)
				(type solid)
			)
			(layer "F.Fab")
		)
		(fp_line
			(start 0.5 0)
			(end -0.5 0)
			(stroke
				(width 0.1)
				(type solid)
			)
			(layer "F.Fab")
		)
		(fp_line
			(start 0 -0.5)
			(end 0 0.5)
			(stroke
				(width 0.1)
				(type solid)
			)
			(layer "F.Fab")
		)
		(fp_line
			(start -0.85 -0.4)
			(end -0.85 0.4)
			(stroke
				(width 0.2)
				(type solid)
			)
			(layer "F.Fab")
		)
		(fp_text user "${REFERENCE}"
			(at -0.00001 0.10711 180)
			(unlocked yes)
			(layer "F.Fab")
			(effects
				(font
					(face "Arial")
					(size 0.63 0.63)
					(thickness 0.1)
				)
				(justify left bottom)
			)
		)
		(pad "1" smd rect
			(at -0.5 0 180)
			(size 0.5 0.6)
			(layers "F.Cu" "F.Mask" "F.Paste")
			(net "NetC5_2")
			(solder_mask_margin 0)
			(solder_paste_margin 0)
		)
		(pad "2" smd rect
			(at 0.5 0 180)
			(size 0.5 0.6)
			(layers "F.Cu" "F.Mask" "F.Paste")
			(net "+3V3")
			(solder_mask_margin 0)
			(solder_paste_margin 0)
		)
	)
)
